(kicad_pcb
	(version 20260206)
	(generator "pcbnew")
	(generator_version "10.0")
	(general
		(thickness 1.6)
		(legacy_teardrops no)
	)
	(paper "A4")
	(title_block
		(title "peb — Lightning_PEB_BRD.brd")
		(comment 1 "Lightning (Wiwynn / Facebook NVMe JBOF) / footprints 85-86 of 2563")
	)
	(layers
		(0 "F.Cu" signal "TOP")
		(4 "In1.Cu" signal "L2GND")
		(6 "In2.Cu" signal "L3")
		(8 "In3.Cu" signal "L4VCC")
		(10 "In4.Cu" signal "L5VCC")
		(12 "In5.Cu" signal "L6")
		(14 "In6.Cu" signal "L7GND")
		(2 "B.Cu" signal "BOTTOM")
		(9 "F.Adhes" user "F.Adhesive")
		(11 "B.Adhes" user "B.Adhesive")
		(13 "F.Paste" user "Package Geometry/Pastemask Top")
		(15 "B.Paste" user "Package Geometry/Pastemask Bottom")
		(5 "F.SilkS" user "Ref Des/Silkscreen Top")
		(7 "B.SilkS" user "Ref Des/Silkscreen Bottom")
		(1 "F.Mask" user "Board Geometry/Soldermask Top")
		(3 "B.Mask" user "Board Geometry/Soldermask Bottom")
		(17 "Dwgs.User" user "User.Drawings")
		(19 "Cmts.User" user "User.Comments")
		(21 "Eco1.User" user "User.Eco1")
		(23 "Eco2.User" user "User.Eco2")
		(25 "Edge.Cuts" user "Board Geometry/Outline")
		(27 "Margin" user)
		(31 "F.CrtYd" user "Package Geometry/Place Bound Top")
		(29 "B.CrtYd" user "Package Geometry/Place Bound Bottom")
		(35 "F.Fab" user "Ref Des/Assembly Top")
		(33 "B.Fab" user "Ref Des/Assembly Bottom")
	)
	(footprint ""
		(layer "F.Cu")
		(at 15.642082 -38.509956)
		(property "Reference" "RJ1"
			(at 0 0 0)
			(layer "F.SilkS")
			(hide yes)
			(effects
				(font
					(size 1.27 1.27)
				)
			)
		)
		(property "Value" "RJ45-LED-12P-10-GP"
			(at -2.15773 -12.96797 0)
			(unlocked yes)
			(layer "F.Fab")
			(hide yes)
			(effects
				(font
					(size 1.016 1.016)
					(thickness 0.1524)
				)
			)
		)
		(property "Device Type" "XRJH-01H-D-H71-D81-W"
			(at -2.15773 -14.49197 0)
			(unlocked yes)
			(layer "F.Fab")
			(hide yes)
			(effects
				(font
					(size 1.016 1.016)
					(thickness 0.1524)
				)
			)
		)
		(duplicate_pad_numbers_are_jumpers no)
		(fp_line
			(start -10.033 -1.2446)
			(end -9.144 -1.2446)
			(stroke
				(width 0.1524)
				(type default)
			)
			(layer "F.SilkS")
		)
		(fp_line
			(start -10.033 1.2446)
			(end -10.033 -1.2446)
			(stroke
				(width 0.1524)
				(type default)
			)
			(layer "F.SilkS")
		)
		(fp_line
			(start -9.144 -11.176)
			(end 9.144 -11.176)
			(stroke
				(width 0.1524)
				(type default)
			)
			(layer "F.SilkS")
		)
		(fp_line
			(start -9.144 -1.2446)
			(end -9.144 -11.176)
			(stroke
				(width 0.1524)
				(type default)
			)
			(layer "F.SilkS")
		)
		(fp_line
			(start -9.144 1.2446)
			(end -10.033 1.2446)
			(stroke
				(width 0.1524)
				(type default)
			)
			(layer "F.SilkS")
		)
		(fp_line
			(start -9.144 13.462)
			(end -9.144 1.2446)
			(stroke
				(width 0.1524)
				(type default)
			)
			(layer "F.SilkS")
		)
		(fp_line
			(start 9.144 -11.176)
			(end 9.144 -1.2446)
			(stroke
				(width 0.1524)
				(type default)
			)
			(layer "F.SilkS")
		)
		(fp_line
			(start 9.144 -1.2446)
			(end 10.033 -1.2446)
			(stroke
				(width 0.1524)
				(type default)
			)
			(layer "F.SilkS")
		)
		(fp_line
			(start 9.144 1.2446)
			(end 9.144 13.462)
			(stroke
				(width 0.1524)
				(type default)
			)
			(layer "F.SilkS")
		)
		(fp_line
			(start 9.144 13.462)
			(end -9.144 13.462)
			(stroke
				(width 0.1524)
				(type default)
			)
			(layer "F.SilkS")
		)
		(fp_line
			(start 10.033 -1.2446)
			(end 10.033 1.2446)
			(stroke
				(width 0.1524)
				(type default)
			)
			(layer "F.SilkS")
		)
		(fp_line
			(start 10.033 1.2446)
			(end 9.144 1.2446)
			(stroke
				(width 0.1524)
				(type default)
			)
			(layer "F.SilkS")
		)
		(fp_circle
			(center -8.789924 0)
			(end -7.443724 0)
			(stroke
				(width 0.3048)
				(type default)
			)
			(fill no)
			(layer "F.SilkS")
		)
		(fp_circle
			(center -7.519924 6.35)
			(end -6.326124 6.35)
			(stroke
				(width 0.3048)
				(type default)
			)
			(fill no)
			(layer "F.SilkS")
		)
		(fp_circle
			(center -7.519924 8.89)
			(end -6.326124 8.89)
			(stroke
				(width 0.3048)
				(type default)
			)
			(fill no)
			(layer "F.SilkS")
		)
		(fp_circle
			(center -6.100064 -9.139936)
			(end -5.084064 -9.139936)
			(stroke
				(width 0.3048)
				(type default)
			)
			(fill no)
			(layer "F.SilkS")
		)
		(fp_circle
			(center -5.07492 -6.599936)
			(end -4.05892 -6.599936)
			(stroke
				(width 0.3048)
				(type default)
			)
			(fill no)
			(layer "F.SilkS")
		)
		(fp_circle
			(center -4.070096 -9.139936)
			(end -3.054096 -9.139936)
			(stroke
				(width 0.3048)
				(type default)
			)
			(fill no)
			(layer "F.SilkS")
		)
		(fp_circle
			(center -3.044952 -6.599936)
			(end -2.028952 -6.599936)
			(stroke
				(width 0.3048)
				(type default)
			)
			(fill no)
			(layer "F.SilkS")
		)
		(fp_circle
			(center -2.040128 -9.139936)
			(end -1.024128 -9.139936)
			(stroke
				(width 0.3048)
				(type default)
			)
			(fill no)
			(layer "F.SilkS")
		)
		(fp_circle
			(center -1.014984 -6.599936)
			(end 0.001016 -6.599936)
			(stroke
				(width 0.3048)
				(type default)
			)
			(fill no)
			(layer "F.SilkS")
		)
		(fp_circle
			(center 1.014984 -6.599936)
			(end 2.030984 -6.599936)
			(stroke
				(width 0.3048)
				(type default)
			)
			(fill no)
			(layer "F.SilkS")
		)
		(fp_circle
			(center 2.040128 -9.139936)
			(end 3.056128 -9.139936)
			(stroke
				(width 0.3048)
				(type default)
			)
			(fill no)
			(layer "F.SilkS")
		)
		(fp_circle
			(center 3.044952 -6.599936)
			(end 4.060952 -6.599936)
			(stroke
				(width 0.3048)
				(type default)
			)
			(fill no)
			(layer "F.SilkS")
		)
		(fp_circle
			(center 4.070096 -9.139936)
			(end 5.086096 -9.139936)
			(stroke
				(width 0.3048)
				(type default)
			)
			(fill no)
			(layer "F.SilkS")
		)
		(fp_circle
			(center 5.07492 -6.599936)
			(end 6.09092 -6.599936)
			(stroke
				(width 0.3048)
				(type default)
			)
			(fill no)
			(layer "F.SilkS")
		)
		(fp_circle
			(center 6.100064 -9.139936)
			(end 7.116064 -9.139936)
			(stroke
				(width 0.3048)
				(type default)
			)
			(fill no)
			(layer "F.SilkS")
		)
		(fp_circle
			(center 7.519924 3.81)
			(end 8.713724 3.81)
			(stroke
				(width 0.3048)
				(type default)
			)
			(fill no)
			(layer "F.SilkS")
		)
		(fp_circle
			(center 7.519924 6.35)
			(end 8.713724 6.35)
			(stroke
				(width 0.3048)
				(type default)
			)
			(fill no)
			(layer "F.SilkS")
		)
		(fp_circle
			(center 7.519924 8.89)
			(end 8.713724 8.89)
			(stroke
				(width 0.3048)
				(type default)
			)
			(fill no)
			(layer "F.SilkS")
		)
		(fp_circle
			(center 8.789924 0)
			(end 10.136124 0)
			(stroke
				(width 0.3048)
				(type default)
			)
			(fill no)
			(layer "F.SilkS")
		)
		(fp_rect
			(start -8.89 13.208)
			(end 8.89 -10.922)
			(stroke
				(width 0)
				(type default)
			)
			(fill no)
			(layer "F.CrtYd")
		)
		(fp_poly
			(pts
				(xy -9.398 13.716) (xy -9.398 1.4986) (xy -10.287 1.4986) (xy -10.287 -1.4986) (xy -9.398 -1.4986)
				(xy -9.398 -11.43) (xy 9.398 -11.43) (xy 9.398 -1.4986) (xy 10.287 -1.4986) (xy 10.287 -0.00635)
				(xy 8.89 -0.00635) (xy 8.89 -10.922) (xy -8.89 -10.922) (xy -8.89 13.208) (xy 8.89 13.208) (xy 8.89 0.00635)
				(xy 10.287 0.00635) (xy 10.287 1.4986) (xy 9.398 1.4986) (xy 9.398 13.716)
			)
			(stroke
				(width 0)
				(type default)
			)
			(fill no)
			(layer "F.CrtYd")
		)
		(fp_poly
			(pts
				(xy -9.398 13.716) (xy -9.398 1.4986) (xy -10.287 1.4986) (xy -10.287 -1.4986) (xy -9.398 -1.4986)
				(xy -9.398 -11.43) (xy 9.398 -11.43) (xy 9.398 -1.4986) (xy 10.287 -1.4986) (xy 10.287 1.4986) (xy 9.398 1.4986)
				(xy 9.398 13.716)
			)
			(stroke
				(width 0)
				(type default)
			)
			(fill no)
			(layer "F.Fab")
		)
		(pad "" np_thru_hole circle
			(at -4.824984 0)
			(size 0.254 0.254)
			(drill 3.2512)
			(layers "*.Cu" "*.Mask")
			(clearance 1.8542)
			(thermal_gap 1.8542)
		)
		(pad "" np_thru_hole circle
			(at 4.824984 0)
			(size 0.254 0.254)
			(drill 3.2512)
			(layers "*.Cu" "*.Mask")
			(clearance 1.8542)
			(thermal_gap 1.8542)
		)
		(pad "1" thru_hole circle
			(at 5.07492 -6.599936)
			(size 1.3208 1.3208)
			(drill 0.9144)
			(layers "*.Cu" "*.Mask")
			(remove_unused_layers no)
			(net "NIC0_CT_POWER")
			(clearance 0.1524)
			(thermal_gap 0.1524)
		)
		(pad "2" thru_hole circle
			(at 3.044952 -6.599936)
			(size 1.3208 1.3208)
			(drill 0.9144)
			(layers "*.Cu" "*.Mask")
			(remove_unused_layers no)
			(net "NIC0_MDI0_N2_R")
			(clearance 0.1524)
			(thermal_gap 0.1524)
		)
		(pad "3" thru_hole circle
			(at 1.014984 -6.599936)
			(size 1.3208 1.3208)
			(drill 0.9144)
			(layers "*.Cu" "*.Mask")
			(remove_unused_layers no)
			(net "NIC0_MDI0_P2_R")
			(clearance 0.1524)
			(thermal_gap 0.1524)
		)
		(pad "4" thru_hole circle
			(at -1.014984 -6.599936)
			(size 1.3208 1.3208)
			(drill 0.9144)
			(layers "*.Cu" "*.Mask")
			(remove_unused_layers no)
			(net "NIC0_MDI0_P1_R")
			(clearance 0.1524)
			(thermal_gap 0.1524)
		)
		(pad "5" thru_hole circle
			(at -3.044952 -6.599936)
			(size 1.3208 1.3208)
			(drill 0.9144)
			(layers "*.Cu" "*.Mask")
			(remove_unused_layers no)
			(net "NIC0_MDI0_N1_R")
			(clearance 0.1524)
			(thermal_gap 0.1524)
		)
		(pad "6" thru_hole circle
			(at -5.07492 -6.599936)
			(size 1.3208 1.3208)
			(drill 0.9144)
			(layers "*.Cu" "*.Mask")
			(remove_unused_layers no)
			(net "NIC0_CT_POWER")
			(clearance 0.1524)
			(thermal_gap 0.1524)
		)
		(pad "7" thru_hole circle
			(at 6.100064 -9.139936)
			(size 1.3208 1.3208)
			(drill 0.9144)
			(layers "*.Cu" "*.Mask")
			(remove_unused_layers no)
			(net "NIC0_CT_POWER")
			(clearance 0.1524)
			(thermal_gap 0.1524)
		)
		(pad "8" thru_hole circle
			(at 4.070096 -9.139936)
			(size 1.3208 1.3208)
			(drill 0.9144)
			(layers "*.Cu" "*.Mask")
			(remove_unused_layers no)
			(net "NIC0_MDI0_P3_R")
			(clearance 0.1524)
			(thermal_gap 0.1524)
		)
		(pad "9" thru_hole circle
			(at 2.040128 -9.139936)
			(size 1.3208 1.3208)
			(drill 0.9144)
			(layers "*.Cu" "*.Mask")
			(remove_unused_layers no)
			(net "NIC0_MDI0_N3_R")
			(clearance 0.1524)
			(thermal_gap 0.1524)
		)
		(pad "10" thru_hole circle
			(at -2.040128 -9.139936)
			(size 1.3208 1.3208)
			(drill 0.9144)
			(layers "*.Cu" "*.Mask")
			(remove_unused_layers no)
			(net "NIC0_MDI0_N0_R")
			(clearance 0.1524)
			(thermal_gap 0.1524)
		)
		(pad "11" thru_hole circle
			(at -4.070096 -9.139936)
			(size 1.3208 1.3208)
			(drill 0.9144)
			(layers "*.Cu" "*.Mask")
			(remove_unused_layers no)
			(net "NIC0_MDI0_P0_R")
			(clearance 0.1524)
			(thermal_gap 0.1524)
		)
		(pad "12" thru_hole circle
			(at -6.100064 -9.139936)
			(size 1.3208 1.3208)
			(drill 0.9144)
			(layers "*.Cu" "*.Mask")
			(remove_unused_layers no)
			(net "NIC0_CT_POWER")
			(clearance 0.1524)
			(thermal_gap 0.1524)
		)
		(pad "13" thru_hole circle
			(at 8.789924 0)
			(size 1.9812 1.9812)
			(drill 1.5748)
			(layers "*.Cu" "*.Mask")
			(remove_unused_layers no)
			(net "GND")
			(clearance 0.1524)
			(thermal_gap 0.1524)
		)
		(pad "14" thru_hole circle
			(at -8.789924 0)
			(size 1.9812 1.9812)
			(drill 1.5748)
			(layers "*.Cu" "*.Mask")
			(remove_unused_layers no)
			(net "GND")
			(clearance 0.1524)
			(thermal_gap 0.1524)
		)
		(pad "D1" thru_hole circle
			(at -7.519924 6.35)
			(size 1.6764 1.6764)
			(drill 1.27)
			(layers "*.Cu" "*.Mask")
			(remove_unused_layers no)
			(net "LED_MDI0_LINK_N")
			(clearance 0.1524)
			(thermal_gap 0.1524)
		)
		(pad "D2" thru_hole circle
			(at -7.519924 8.89)
			(size 1.6764 1.6764)
			(drill 1.27)
			(layers "*.Cu" "*.Mask")
			(remove_unused_layers no)
			(net "LED_MDI0_ACT")
			(clearance 0.1524)
			(thermal_gap 0.1524)
		)
		(pad "D3" thru_hole circle
			(at 7.519924 3.81)
			(size 1.6764 1.6764)
			(drill 1.27)
			(layers "*.Cu" "*.Mask")
			(remove_unused_layers no)
			(net "LED_MDI0_1G_N_R")
			(clearance 0.1524)
			(thermal_gap 0.1524)
		)
		(pad "D4" thru_hole circle
			(at 7.519924 6.35)
			(size 1.6764 1.6764)
			(drill 1.27)
			(layers "*.Cu" "*.Mask")
			(remove_unused_layers no)
			(net "LED_MDI0_100M_1G_N")
			(clearance 0.1524)
			(thermal_gap 0.1524)
		)
		(pad "D5" thru_hole circle
			(at 7.519924 8.89)
			(size 1.6764 1.6764)
			(drill 1.27)
			(layers "*.Cu" "*.Mask")
			(remove_unused_layers no)
			(net "LED_MDI0_100M_N_R")
			(clearance 0.1524)
			(thermal_gap 0.1524)
		)
		(zone
			(layer "F.Cu")
			(hatch none 0.5)
			(connect_pads
				(clearance 0)
			)
			(min_thickness 0.25)
			(keepout
				(tracks allowed)
				(vias not_allowed)
				(pads allowed)
				(copperpour not_allowed)
				(footprints allowed)
			)
			(placement
				(enabled no)
				(sheetname "")
			)
			(fill
				(thermal_gap 0.5)
				(thermal_bridge_width 0.5)
				(island_removal_mode 0)
			)
			(polygon
				(pts
					(xy 6.452108 -40.099996) (xy 6.452108 -42.69994) (xy 8.55218 -42.69994) (xy 8.55218 -40.099996)
				)
			)
		)
		(zone
			(layer "F.Cu")
			(hatch none 0.5)
			(connect_pads
				(clearance 0)
			)
			(min_thickness 0.25)
			(keepout
				(tracks not_allowed)
				(vias allowed)
				(pads allowed)
				(copperpour not_allowed)
				(footprints allowed)
			)
			(placement
				(enabled no)
				(sheetname "")
			)
			(fill
				(thermal_gap 0.5)
				(thermal_bridge_width 0.5)
				(island_removal_mode 0)
			)
			(polygon
				(pts
					(xy 6.452108 -40.099996) (xy 8.55218 -40.099996) (xy 8.55218 -42.69994) (xy 6.452108 -42.69994)
				)
			)
		)
		(zone
			(layer "F.Cu")
			(hatch none 0.5)
			(connect_pads
				(clearance 0)
			)
			(min_thickness 0.25)
			(keepout
				(tracks not_allowed)
				(vias allowed)
				(pads allowed)
				(copperpour not_allowed)
				(footprints allowed)
			)
			(placement
				(enabled no)
				(sheetname "")
			)
			(fill
				(thermal_gap 0.5)
				(thermal_bridge_width 0.5)
				(island_removal_mode 0)
			)
			(polygon
				(pts
					(xy 22.731984 -40.099996) (xy 24.832056 -40.099996) (xy 24.832056 -42.69994) (xy 22.731984 -42.69994)
				)
			)
		)
		(zone
			(layer "F.Cu")
			(hatch none 0.5)
			(connect_pads
				(clearance 0)
			)
			(min_thickness 0.25)
			(keepout
				(tracks allowed)
				(vias not_allowed)
				(pads allowed)
				(copperpour not_allowed)
				(footprints allowed)
			)
			(placement
				(enabled no)
				(sheetname "")
			)
			(fill
				(thermal_gap 0.5)
				(thermal_bridge_width 0.5)
				(island_removal_mode 0)
			)
			(polygon
				(pts
					(xy 24.832056 -40.099996) (xy 24.832056 -42.69994) (xy 22.731984 -42.69994) (xy 22.731984 -40.099996)
				)
			)
		)
		(zone
			(layer "F.Cu")
			(hatch none 0.5)
			(connect_pads
				(clearance 0)
			)
			(min_thickness 0.25)
			(keepout
				(tracks not_allowed)
				(vias allowed)
				(pads allowed)
				(copperpour not_allowed)
				(footprints allowed)
			)
			(placement
				(enabled no)
				(sheetname "")
			)
			(fill
				(thermal_gap 0.5)
				(thermal_bridge_width 0.5)
				(island_removal_mode 0)
			)
			(polygon
				(pts
					(xy 6.452108 -24.99995) (xy 24.832056 -24.99995) (xy 24.832056 -28.549854) (xy 22.323806 -28.549854)
					(xy 22.323806 -34.500058) (xy 8.960358 -34.500058) (xy 8.960358 -28.549854) (xy 6.452108 -28.549854)
				)
			)
		)
		(zone
			(layer "F.Cu")
			(hatch none 0.5)
			(connect_pads
				(clearance 0)
			)
			(min_thickness 0.25)
			(keepout
				(tracks allowed)
				(vias not_allowed)
				(pads allowed)
				(copperpour not_allowed)
				(footprints allowed)
			)
			(placement
				(enabled no)
				(sheetname "")
			)
			(fill
				(thermal_gap 0.5)
				(thermal_bridge_width 0.5)
				(island_removal_mode 0)
			)
			(polygon
				(pts
					(xy 6.452108 -24.99995) (xy 24.832056 -24.99995) (xy 24.832056 -28.549854) (xy 22.323806 -28.549854)
					(xy 22.323806 -34.500058) (xy 8.960358 -34.500058) (xy 8.960358 -28.549854) (xy 6.452108 -28.549854)
				)
			)
		)
		(zone
			(layers "F.Cu" "B.Cu" "In1.Cu" "In2.Cu" "In3.Cu" "In4.Cu" "In5.Cu" "In6.Cu")
			(hatch none 0.5)
			(connect_pads
				(clearance 0)
			)
			(min_thickness 0.25)
			(keepout
				(tracks not_allowed)
				(vias allowed)
				(pads allowed)
				(copperpour not_allowed)
				(footprints allowed)
			)
			(placement
				(enabled no)
				(sheetname "")
			)
			(fill
				(thermal_gap 0.5)
				(thermal_bridge_width 0.5)
				(island_removal_mode 0)
			)
			(polygon
				(pts
					(arc
						(start 12.747498 -38.509956)
						(mid 8.886698 -38.509956)
						(end 12.747498 -38.509956)
					)
				)
			)
		)
		(zone
			(layers "F.Cu" "B.Cu" "In1.Cu" "In2.Cu" "In3.Cu" "In4.Cu" "In5.Cu" "In6.Cu")
			(hatch none 0.5)
			(connect_pads
				(clearance 0)
			)
			(min_thickness 0.25)
			(keepout
				(tracks not_allowed)
				(vias allowed)
				(pads allowed)
				(copperpour not_allowed)
				(footprints allowed)
			)
			(placement
				(enabled no)
				(sheetname "")
			)
			(fill
				(thermal_gap 0.5)
				(thermal_bridge_width 0.5)
				(island_removal_mode 0)
			)
			(polygon
				(pts
					(arc
						(start 22.397466 -38.509956)
						(mid 18.536666 -38.509956)
						(end 22.397466 -38.509956)
					)
				)
			)
		)
	)
	(footprint ""
		(layer "F.Cu")
		(at 276.606 -1.27 90)
		(property "Reference" "R2905"
			(at 0 0 90)
			(layer "F.SilkS")
			(hide yes)
			(effects
				(font
					(size 1.27 1.27)
				)
			)
		)
		(property "Value" "0R2J-2-GP"
			(at 0.064008 -3.993896 90)
			(unlocked yes)
			(layer "F.Fab")
			(hide yes)
			(effects
				(font
					(size 1.016 1.016)
					(thickness 0.1524)
				)
			)
		)
		(property "Device Type" "R402H16"
			(at 0.064008 -5.517896 90)
			(unlocked yes)
			(layer "F.Fab")
			(hide yes)
			(effects
				(font
					(size 1.016 1.016)
					(thickness 0.1524)
				)
			)
		)
		(duplicate_pad_numbers_are_jumpers no)
		(fp_line
			(start 0.508 -0.9398)
			(end -0.508 -0.9398)
			(stroke
				(width 0.1524)
				(type default)
			)
			(layer "F.SilkS")
		)
		(fp_line
			(start -0.508 -0.9398)
			(end -0.508 0.9398)
			(stroke
				(width 0.1524)
				(type default)
			)
			(layer "F.SilkS")
		)
		(fp_rect
			(start -0.508 0.9398)
			(end 0.508 -0.9398)
			(stroke
				(width 0)
				(type default)
			)
			(fill no)
			(layer "F.CrtYd")
		)
		(fp_rect
			(start -0.508 0.9398)
			(end 0.508 -0.9398)
			(stroke
				(width 0)
				(type default)
			)
			(fill no)
			(layer "F.Fab")
		)
		(pad "1" smd custom
			(at 0 -0.4445 90)
			(size 0.1397 0.1397)
			(layers "F.Cu" "F.Mask" "F.Paste")
			(net "BMC_I2C13_MINI7_SDA")
			(options
				(clearance outline)
				(anchor circle)
			)
			(primitives
				(gr_poly
					(pts
						(arc
							(start -0.1778 -0.2794)
							(mid -0.249642 -0.249642)
							(end -0.2794 -0.1778)
						)
						(arc
							(start -0.2794 0.1778)
							(mid -0.249642 0.249642)
							(end -0.1778 0.2794)
						)
						(arc
							(start 0.1778 0.2794)
							(mid 0.249642 0.249642)
							(end 0.2794 0.1778)
						)
						(arc
							(start 0.2794 -0.1778)
							(mid 0.249642 -0.249642)
							(end 0.1778 -0.2794)
						)
					)
					(width 0)
					(fill yes)
				)
			)
		)
		(pad "2" smd custom
			(at 0 0.4445 90)
			(size 0.1397 0.1397)
			(layers "F.Cu" "F.Mask" "F.Paste")
			(net "8644_SDA_R_7")
			(options
				(clearance outline)
				(anchor circle)
			)
			(primitives
				(gr_poly
					(pts
						(arc
							(start -0.1778 -0.2794)
							(mid -0.249642 -0.249642)
							(end -0.2794 -0.1778)
						)
						(arc
							(start -0.2794 0.1778)
							(mid -0.249642 0.249642)
							(end -0.1778 0.2794)
						)
						(arc
							(start 0.1778 0.2794)
							(mid 0.249642 0.249642)
							(end 0.2794 0.1778)
						)
						(arc
							(start 0.2794 -0.1778)
							(mid 0.249642 -0.249642)
							(end 0.1778 -0.2794)
						)
					)
					(width 0)
					(fill yes)
				)
			)
		)
	)
)
